# S9S_MB_2U (Grand Teton) — schematic netlist excerpt (pin names and nets, part order shuffled) for the footprints in the layout excerpt that follows; sources: Cadence DE-HDL packaged netlist, KiCad conversion of 03242023_DA0F0TMBIJ0_F0T_Motherboard_J_brd_V01_OCP.brd

PC2368  Q_CAP  0.1UF 25V 10% EMPTY  pkg 0402  page 296 : A = PVCCD_HV_CPU1_VCC ; B = GND
PR1768  Q_RES  3.3 1% CHIP  pkg 0402LF  page 268 : A = SW_PVCCIN_CPU0_BOOT4 ; B = SW_PVCCIN_CPU0_BOOT4_R

(kicad_pcb
	(version 20260206)
	(generator "pcbnew")
	(generator_version "10.0")
	(general
		(thickness 1.6)
		(legacy_teardrops no)
	)
	(paper "A4")
	(title_block
		(title "03242023_DA0F0TMBIJ0_F0T_Motherboard_J_brd_V01_OCP.brd")
		(comment 1 "Grand Teton / footprints 3758-3759 of 6105")
	)
	(layers
		(0 "F.Cu" signal "TOP")
		(4 "In1.Cu" signal "GND")
		(6 "In2.Cu" signal "IN1")
		(8 "In3.Cu" signal "GND1")
		(10 "In4.Cu" signal "IN2")
		(12 "In5.Cu" signal "GND2")
		(14 "In6.Cu" signal "IN3")
		(16 "In7.Cu" signal "GND3")
		(18 "In8.Cu" signal "VCC")
		(20 "In9.Cu" signal "VCC1")
		(22 "In10.Cu" signal "GND4")
		(24 "In11.Cu" signal "IN4")
		(26 "In12.Cu" signal "GND5")
		(28 "In13.Cu" signal "IN5")
		(30 "In14.Cu" signal "GND6")
		(32 "In15.Cu" signal "IN6")
		(34 "In16.Cu" signal "GND7")
		(2 "B.Cu" signal "BOTTOM")
		(9 "F.Adhes" user "F.Adhesive")
		(11 "B.Adhes" user "B.Adhesive")
		(13 "F.Paste" user "Package Geometry/Pastemask Top")
		(15 "B.Paste" user "Package Geometry/Pastemask Bottom")
		(5 "F.SilkS" user "Ref Des/Silkscreen Top")
		(7 "B.SilkS" user "Ref Des/Silkscreen Bottom")
		(1 "F.Mask" user "Board Geometry/Soldermask Top")
		(3 "B.Mask" user "Board Geometry/Soldermask Bottom")
		(17 "Dwgs.User" user "User.Drawings")
		(19 "Cmts.User" user "User.Comments")
		(21 "Eco1.User" user "User.Eco1")
		(23 "Eco2.User" user "User.Eco2")
		(25 "Edge.Cuts" user "Board Geometry/Outline")
		(27 "Margin" user)
		(31 "F.CrtYd" user "Package Geometry/Place Bound Top")
		(29 "B.CrtYd" user "Package Geometry/Place Bound Bottom")
		(35 "F.Fab" user "Ref Des/Assembly Top")
		(33 "B.Fab" user "Ref Des/Assembly Bottom")
	)
	(footprint ""
		(layer "F.Cu")
		(at 370.17833 -338.17814 90)
		(property "Reference" "PR1768"
			(at 0 0 90)
			(layer "F.SilkS")
			(hide yes)
			(effects
				(font
					(size 1.27 1.27)
				)
			)
		)
		(property "Value" ""
			(at 0 0 90)
			(layer "F.Fab")
			(effects
				(font
					(size 1.27 1.27)
				)
			)
		)
		(duplicate_pad_numbers_are_jumpers no)
		(fp_line
			(start 0.7874 -0.4064)
			(end 0.7874 0.4064)
			(stroke
				(width 0.1524)
				(type default)
			)
			(layer "F.SilkS")
		)
		(fp_line
			(start -0.7874 -0.4064)
			(end 0.7874 -0.4064)
			(stroke
				(width 0.1524)
				(type default)
			)
			(layer "F.SilkS")
		)
		(fp_line
			(start 0.7874 0.4064)
			(end -0.7874 0.4064)
			(stroke
				(width 0.1524)
				(type default)
			)
			(layer "F.SilkS")
		)
		(fp_line
			(start -0.7874 0.4064)
			(end -0.7874 -0.4064)
			(stroke
				(width 0.1524)
				(type default)
			)
			(layer "F.SilkS")
		)
		(fp_line
			(start -0.12065 -0.305054)
			(end -0.12065 -0.2794)
			(stroke
				(width 0.1)
				(type default)
			)
			(layer "F.Fab")
		)
		(fp_line
			(start -0.67945 -0.305054)
			(end -0.12065 -0.305054)
			(stroke
				(width 0.1)
				(type default)
			)
			(layer "F.Fab")
		)
		(fp_line
			(start 0.67945 -0.3048)
			(end 0.67945 0.3048)
			(stroke
				(width 0.1)
				(type default)
			)
			(layer "F.Fab")
		)
		(fp_line
			(start 0.12065 -0.3048)
			(end 0.67945 -0.3048)
			(stroke
				(width 0.1)
				(type default)
			)
			(layer "F.Fab")
		)
		(fp_line
			(start 0.12065 -0.2794)
			(end 0.12065 -0.3048)
			(stroke
				(width 0.1)
				(type default)
			)
			(layer "F.Fab")
		)
		(fp_line
			(start -0.12065 -0.2794)
			(end 0.12065 -0.2794)
			(stroke
				(width 0.1)
				(type default)
			)
			(layer "F.Fab")
		)
		(fp_line
			(start 0.120396 0.2794)
			(end -0.12065 0.2794)
			(stroke
				(width 0.1)
				(type default)
			)
			(layer "F.Fab")
		)
		(fp_line
			(start -0.12065 0.2794)
			(end -0.12065 0.3048)
			(stroke
				(width 0.1)
				(type default)
			)
			(layer "F.Fab")
		)
		(fp_line
			(start 0.67945 0.3048)
			(end 0.120396 0.3048)
			(stroke
				(width 0.1)
				(type default)
			)
			(layer "F.Fab")
		)
		(fp_line
			(start 0.120396 0.3048)
			(end 0.120396 0.2794)
			(stroke
				(width 0.1)
				(type default)
			)
			(layer "F.Fab")
		)
		(fp_line
			(start -0.12065 0.3048)
			(end -0.67945 0.3048)
			(stroke
				(width 0.1)
				(type default)
			)
			(layer "F.Fab")
		)
		(fp_line
			(start -0.67945 0.3048)
			(end -0.67945 -0.305054)
			(stroke
				(width 0.1)
				(type default)
			)
			(layer "F.Fab")
		)
		(pad "1" smd circle
			(at -0.40005 0 90)
			(size 0 0)
			(layers "F.Cu" "F.Mask" "F.Paste")
			(net "SW_PVCCIN_CPU0_BOOT4")
		)
		(pad "2" smd circle
			(at 0.40005 0 90)
			(size 0 0)
			(layers "F.Cu" "F.Mask" "F.Paste")
			(net "SW_PVCCIN_CPU0_BOOT4_R")
		)
	)
	(footprint ""
		(layer "F.Cu")
		(at 31.5341 -170.0276)
		(property "Reference" "PC2368"
			(at 0 0 0)
			(layer "F.SilkS")
			(hide yes)
			(effects
				(font
					(size 1.27 1.27)
				)
			)
		)
		(property "Value" ""
			(at 0 0 0)
			(layer "F.Fab")
			(effects
				(font
					(size 1.27 1.27)
				)
			)
		)
		(duplicate_pad_numbers_are_jumpers no)
		(fp_line
			(start -0.7874 -0.4064)
			(end 0.7874 -0.4064)
			(stroke
				(width 0.1524)
				(type default)
			)
			(layer "F.SilkS")
		)
		(fp_line
			(start -0.7874 0.4064)
			(end -0.7874 -0.4064)
			(stroke
				(width 0.1524)
				(type default)
			)
			(layer "F.SilkS")
		)
		(fp_line
			(start 0.7874 -0.4064)
			(end 0.7874 0.4064)
			(stroke
				(width 0.1524)
				(type default)
			)
			(layer "F.SilkS")
		)
		(fp_line
			(start 0.7874 0.4064)
			(end -0.7874 0.4064)
			(stroke
				(width 0.1524)
				(type default)
			)
			(layer "F.SilkS")
		)
		(fp_line
			(start -0.67945 -0.305054)
			(end -0.12065 -0.305054)
			(stroke
				(width 0.1)
				(type default)
			)
			(layer "F.Fab")
		)
		(fp_line
			(start -0.67945 0.3048)
			(end -0.67945 -0.305054)
			(stroke
				(width 0.1)
				(type default)
			)
			(layer "F.Fab")
		)
		(fp_line
			(start -0.12065 -0.305054)
			(end -0.12065 -0.2794)
			(stroke
				(width 0.1)
				(type default)
			)
			(layer "F.Fab")
		)
		(fp_line
			(start -0.12065 -0.2794)
			(end 0.12065 -0.2794)
			(stroke
				(width 0.1)
				(type default)
			)
			(layer "F.Fab")
		)
		(fp_line
			(start -0.12065 0.2794)
			(end -0.12065 0.3048)
			(stroke
				(width 0.1)
				(type default)
			)
			(layer "F.Fab")
		)
		(fp_line
			(start -0.12065 0.3048)
			(end -0.67945 0.3048)
			(stroke
				(width 0.1)
				(type default)
			)
			(layer "F.Fab")
		)
		(fp_line
			(start 0.120396 0.2794)
			(end -0.12065 0.2794)
			(stroke
				(width 0.1)
				(type default)
			)
			(layer "F.Fab")
		)
		(fp_line
			(start 0.120396 0.3048)
			(end 0.120396 0.2794)
			(stroke
				(width 0.1)
				(type default)
			)
			(layer "F.Fab")
		)
		(fp_line
			(start 0.12065 -0.3048)
			(end 0.67945 -0.3048)
			(stroke
				(width 0.1)
				(type default)
			)
			(layer "F.Fab")
		)
		(fp_line
			(start 0.12065 -0.2794)
			(end 0.12065 -0.3048)
			(stroke
				(width 0.1)
				(type default)
			)
			(layer "F.Fab")
		)
		(fp_line
			(start 0.67945 -0.3048)
			(end 0.67945 0.3048)
			(stroke
				(width 0.1)
				(type default)
			)
			(layer "F.Fab")
		)
		(fp_line
			(start 0.67945 0.3048)
			(end 0.120396 0.3048)
			(stroke
				(width 0.1)
				(type default)
			)
			(layer "F.Fab")
		)
		(pad "1" smd circle
			(at -0.40005 0)
			(size 0 0)
			(layers "F.Cu" "F.Mask" "F.Paste")
			(net "PVCCD_HV_CPU1_VCC")
		)
		(pad "2" smd circle
			(at 0.40005 0)
			(size 0 0)
			(layers "F.Cu" "F.Mask" "F.Paste")
			(net "GND")
		)
	)
)
